# S9S_MB_2U (Grand Teton) — schematic parts with pin connectivity, parts 1602–1602 of 6093; source: Cadence DE-HDL packaged netlist (pstxprt.dat, pstxnet.dat, pstchip.dat)

J9  SCONN288_ADR50017P130CC  SCONN288_ADR50017-P130CC IO  pkg DDR288S_1-1VXB  page 90
  1  VIN_BULK0  POWER  = P12V_S3_AUX_CPU0_NVDIMM
  2  RFU0  TRI  = TP_CHE_CPU0_DIMM1_FRU_0
  3  VIN_MGMT  POWER  = P3V3_AUX
  4  HSCL  IN  = I3C_SPD_DDREFGH_CPU0_LVC1_SCL_R
  5  HSDA  BI  = I3C_SPD_DDREFGH_CPU0_LVC1_SDA
  6  VSS0  POWER  = GND
  7  DQ0_A  BI  = M_E_CPU0_SA_DQ<0>
  8  VSS1  POWER  = GND
  9  DQ1_A  BI  = M_E_CPU0_SA_DQ<1>
  10  VSS2  POWER  = GND
  11  DQS0_A_T  BI  = M_E_CPU0_SA_DQS_DP<0>
  12  DQS0_A_C  BI  = M_E_CPU0_SA_DQS_DN<0>
  13  VSS3  POWER  = GND
  14  DQ4_A  BI  = M_E_CPU0_SA_DQ<4>
  15  VSS4  POWER  = GND
  16  DQ5_A  BI  = M_E_CPU0_SA_DQ<5>
  17  VSS5  POWER  = GND
  18  DQ8_A  BI  = M_E_CPU0_SA_DQ<8>
  19  VSS6  POWER  = GND
  20  DQ9_A  BI  = M_E_CPU0_SA_DQ<9>
  21  VSS7  POWER  = GND
  22  DQS1_A_T  BI  = M_E_CPU0_SA_DQS_DP<1>
  23  DQS1_A_C  BI  = M_E_CPU0_SA_DQS_DN<1>
  24  VSS8  POWER  = GND
  25  DQ12_A  BI  = M_E_CPU0_SA_DQ<12>
  26  VSS9  POWER  = GND
  27  DQ13_A  BI  = M_E_CPU0_SA_DQ<13>
  28  VSS10  POWER  = GND
  29  DQ16_A  BI  = M_E_CPU0_SA_DQ<16>
  30  VSS11  POWER  = GND
  31  DQ17_A  BI  = M_E_CPU0_SA_DQ<17>
  32  VSS12  POWER  = GND
  33  DQS2_A_T  BI  = M_E_CPU0_SA_DQS_DP<2>
  34  DQS2_A_C  BI  = M_E_CPU0_SA_DQS_DN<2>
  35  VSS13  POWER  = GND
  36  DQ20_A  BI  = M_E_CPU0_SA_DQ<20>
  37  VSS14  POWER  = GND
  38  DQ21_A  BI  = M_E_CPU0_SA_DQ<21>
  39  VSS15  POWER  = GND
  40  DQ24_A  BI  = M_E_CPU0_SA_DQ<24>
  41  VSS16  POWER  = GND
  42  DQ25_A  BI  = M_E_CPU0_SA_DQ<25>
  43  VSS17  POWER  = GND
  44  DQS3_A_T  BI  = M_E_CPU0_SA_DQS_DP<3>
  45  DQS3_A_C  BI  = M_E_CPU0_SA_DQS_DN<3>
  46  VSS18  POWER  = GND
  47  DQ28_A  BI  = M_E_CPU0_SA_DQ<28>
  48  VSS19  POWER  = GND
  49  DQ29_A  BI  = M_E_CPU0_SA_DQ<29>
  50  VSS20  POWER  = GND
  51  CB0_A  BI  = M_E_CPU0_SA_CB<0>
  52  VSS21  POWER  = GND
  53  CB1_A  BI  = M_E_CPU0_SA_CB<1>
  54  VSS22  POWER  = GND
  55  DQS4_A_T  BI  = M_E_CPU0_SA_DQS_DP<4>
  56  DQS4_A_C  BI  = M_E_CPU0_SA_DQS_DN<4>
  57  VSS23  POWER  = GND
  58  CB4_A  BI  = M_E_CPU0_SA_CB<4>
  59  VSS24  POWER  = GND
  60  CB5_A  BI  = M_E_CPU0_SA_CB<5>
  61  VSS25  POWER  = GND
  62  ALERT_N  OUT  = M_E_CPU0_ALERT_N
  63  VSS26  POWER  = GND
  64  CS0_A_N  IN  = M_E_CPU0_SA_CS_N<0>
  65  VSS27  POWER  = GND
  66  CA0_A  IN  = M_E_CPU0_SA_CA<0>
  67  VSS28  POWER  = GND
  68  CA2_A  IN  = M_E_CPU0_SA_CA<2>
  69  VSS29  POWER  = GND
  70  CA4_A  IN  = M_E_CPU0_SA_CA<4>
  71  VSS30  POWER  = GND
  72  CA6_A  IN  = M_E_CPU0_SA_CA<6>
  73  VSS31  POWER  = GND
  74  PAR_A  IN  = M_E_CPU0_SA_PAR
  75  VSS32  POWER  = GND
  76  CA0_B  IN  = M_E_CPU0_SB_CA<0>
  77  VSS33  POWER  = GND
  78  CA2_B  IN  = M_E_CPU0_SB_CA<2>
  79  VSS34  POWER  = GND
  80  CA4_B  IN  = M_E_CPU0_SB_CA<4>
  81  VSS35  POWER  = GND
  82  CA6_B  IN  = M_E_CPU0_SB_CA<6>
  83  VSS36  POWER  = GND
  84  CS0_B_N  IN  = M_E_CPU0_SB_CS_N<0>
  85  VSS37  POWER  = GND
  86  \lbd||rsp_a_n\  OUT  = M_E_CPU0_SA_RSP<0>
  87  \lbs||rsp_b_n\  OUT  = M_E_CPU0_SB_RSP<0>
  88  VSS38  POWER  = GND
  89  CB4_B  BI  = M_E_CPU0_SB_CB<4>
  90  VSS39  POWER  = GND
  91  CB5_B  BI  = M_E_CPU0_SB_CB<5>
  92  VSS40  POWER  = GND
  93  \dqs9_b_t||tdqs9_b_t||dbi4_b_n\  BI  = M_E_CPU0_SB_DQS_DP<9>
  94  \dqs9_b_c||tdqs9_b_c\  BI  = M_E_CPU0_SB_DQS_DN<9>
  95  VSS41  POWER  = GND
  96  CB0_B  BI  = M_E_CPU0_SB_CB<0>
  97  VSS42  POWER  = GND
  98  CB1_B  BI  = M_E_CPU0_SB_CB<1>
  99  VSS43  POWER  = GND
  100  DQ0_B  BI  = M_E_CPU0_SB_DQ<0>
  101  VSS44  POWER  = GND
  102  DQ1_B  BI  = M_E_CPU0_SB_DQ<1>
  103  VSS45  POWER  = GND
  104  DQS0_B_T  BI  = M_E_CPU0_SB_DQS_DP<0>
  105  DQS0_B_C  BI  = M_E_CPU0_SB_DQS_DN<0>
  106  VSS46  POWER  = GND
  107  DQ4_B  BI  = M_E_CPU0_SB_DQ<4>
  108  VSS47  POWER  = GND
  109  DQ5_B  BI  = M_E_CPU0_SB_DQ<5>
  110  VSS48  POWER  = GND
  111  DQ8_B  BI  = M_E_CPU0_SB_DQ<8>
  112  VSS49  POWER  = GND
  113  DQ9_B  BI  = M_E_CPU0_SB_DQ<9>
  114  VSS50  POWER  = GND
  115  DQS1_B_T  BI  = M_E_CPU0_SB_DQS_DP<1>
  116  DQS1_B_C  BI  = M_E_CPU0_SB_DQS_DN<1>
  117  VSS51  POWER  = GND
  118  DQ12_B  BI  = M_E_CPU0_SB_DQ<12>
  119  VSS52  POWER  = GND
  120  DQ13_B  BI  = M_E_CPU0_SB_DQ<13>
  121  VSS53  POWER  = GND
  122  DQ16_B  BI  = M_E_CPU0_SB_DQ<16>
  123  VSS54  POWER  = GND
  124  DQ17_B  BI  = M_E_CPU0_SB_DQ<17>
  125  VSS55  POWER  = GND
  126  DQS2_B_T  BI  = M_E_CPU0_SB_DQS_DP<2>
  127  DQS2_B_C  BI  = M_E_CPU0_SB_DQS_DN<2>
  128  VSS56  POWER  = GND
  129  DQ20_B  BI  = M_E_CPU0_SB_DQ<20>
  130  VSS57  POWER  = GND
  131  DQ21_B  BI  = M_E_CPU0_SB_DQ<21>
  132  VSS58  POWER  = GND
  133  DQ24_B  BI  = M_E_CPU0_SB_DQ<24>
  134  VSS59  POWER  = GND
  135  DQ25_B  BI  = M_E_CPU0_SB_DQ<25>
  136  VSS60  POWER  = GND
  137  DQS3_B_T  BI  = M_E_CPU0_SB_DQS_DP<3>
  138  DQS3_B_C  BI  = M_E_CPU0_SB_DQS_DN<3>
  139  VSS61  POWER  = GND
  140  DQ28_B  BI  = M_E_CPU0_SB_DQ<28>
  141  VSS62  POWER  = GND
  142  DQ29_B  BI  = M_E_CPU0_SB_DQ<29>
  143  VSS63  POWER  = GND
  144  RFU1  TRI  = TP_CHE_CPU0_DIMM1_FRU_1
  145  VIN_BULK1  POWER  = P12V_S3_AUX_CPU0_NVDIMM
  146  VIN_BULK2  POWER  = P12V_S3_AUX_CPU0_NVDIMM
  147  \pwr_good||fail_n\  BI  = PWRGD_CHE_CPU0_DIMM1
  148  HSA  IN  = PD_CHE_CPU0_DIMM1_SAA
  149  RFU2  TRI  = TP_CHE_CPU0_DIMM1_FRU_2
  150  RFU3  TRI  = TP_CHE_CPU0_DIMM1_FRU_3
  151  VSS64  POWER  = GND
  152  DQ2_A  BI  = M_E_CPU0_SA_DQ<2>
  153  VSS65  POWER  = GND
  154  DQ3_A  BI  = M_E_CPU0_SA_DQ<3>
  155  VSS66  POWER  = GND
  156  \dqs5_a_c||tdqs5_a_c||dqs5_a_t||tdqs5_a_t\  BI  = M_E_CPU0_SA_DQS_DN<5>
  157  \dqs5_a_t||tdqs5_a_t\  BI  = M_E_CPU0_SA_DQS_DP<5>
  158  VSS67  POWER  = GND
  159  DQ6_A  BI  = M_E_CPU0_SA_DQ<6>
  160  VSS68  POWER  = GND
  161  DQ7_A  BI  = M_E_CPU0_SA_DQ<7>
  162  VSS69  POWER  = GND
  163  DQ10_A  BI  = M_E_CPU0_SA_DQ<10>
  164  VSS70  POWER  = GND
  165  DQ11_A  BI  = M_E_CPU0_SA_DQ<11>
  166  VSS71  POWER  = GND
  167  \dqs6_a_c||tdqs6_a_c||dqs6_a_t||tdqs6_a_t\  BI  = M_E_CPU0_SA_DQS_DN<6>
  168  \dqs6_a_t||tdqs6_a_t\  BI  = M_E_CPU0_SA_DQS_DP<6>
  169  VSS72  POWER  = GND
  170  DQ14_A  BI  = M_E_CPU0_SA_DQ<14>
  171  VSS73  POWER  = GND
  172  DQ15_A  BI  = M_E_CPU0_SA_DQ<15>
  173  VSS74  POWER  = GND
  174  DQ18_A  BI  = M_E_CPU0_SA_DQ<18>
  175  VSS75  POWER  = GND
  176  DQ19_A  BI  = M_E_CPU0_SA_DQ<19>
  177  VSS76  POWER  = GND
  178  \dqs7_a_c||tdqs7_a_c\  BI  = M_E_CPU0_SA_DQS_DN<7>
  179  \dqs7_a_t||tdqs7_a_t\  BI  = M_E_CPU0_SA_DQS_DP<7>
  180  VSS77  POWER  = GND
  181  DQ22_A  BI  = M_E_CPU0_SA_DQ<22>
  182  VSS78  POWER  = GND
  183  DQ23_A  BI  = M_E_CPU0_SA_DQ<23>
  184  VSS79  POWER  = GND
  185  DQ26_A  BI  = M_E_CPU0_SA_DQ<26>
  186  VSS80  POWER  = GND
  187  DQ27_A  BI  = M_E_CPU0_SA_DQ<27>
  188  VSS81  POWER  = GND
  189  \dqs8_a_c||tdqs8_a_c\  BI  = M_E_CPU0_SA_DQS_DN<8>
  190  \dqs8_a_t||tdqs8_a_t\  BI  = M_E_CPU0_SA_DQS_DP<8>
  191  VSS82  POWER  = GND
  192  DQ30_A  BI  = M_E_CPU0_SA_DQ<30>
  193  VSS83  POWER  = GND
  194  DQ31_A  BI  = M_E_CPU0_SA_DQ<31>
  195  VSS84  POWER  = GND
  196  CB2_A  BI  = M_E_CPU0_SA_CB<2>
  197  VSS85  POWER  = GND
  198  CB3_A  BI  = M_E_CPU0_SA_CB<3>
  199  VSS86  POWER  = GND
  200  \dqs9_a_c||tdqs9_a_c\  BI  = M_E_CPU0_SA_DQS_DN<9>
  201  \dqs9_a_t||tdqs9_a_t\  BI  = M_E_CPU0_SA_DQS_DP<9>
  202  VSS87  POWER  = GND
  203  CB6_A  BI  = M_E_CPU0_SA_CB<6>
  204  VSS88  POWER  = GND
  205  CB7_A  BI  = M_E_CPU0_SA_CB<7>
  206  VSS89  POWER  = GND
  207  RESET_N  IN  = RST_M_EF_CPU0_FPGA_N
  208  VSS90  POWER  = GND
  209  CS1_A_N  IN  = M_E_CPU0_SA_CS_N<1>
  210  VSS91  POWER  = GND
  211  CA1_A  IN  = M_E_CPU0_SA_CA<1>
  212  VSS92  POWER  = GND
  213  CA3_A  IN  = M_E_CPU0_SA_CA<3>
  214  VSS93  POWER  = GND
  215  CA5_A  IN  = M_E_CPU0_SA_CA<5>
  216  VSS94  POWER  = GND
  217  CK_T  IN  = M_E_CPU0_CLK_DP<0>
  218  CK_C  IN  = M_E_CPU0_CLK_DN<0>
  219  VSS95  POWER  = GND
  220  RFU4  TRI  = TP_CHE_CPU0_DIMM1_FRU_4
  221  CA1_B  IN  = M_E_CPU0_SB_CA<1>
  222  VSS96  POWER  = GND
  223  CA3_B  IN  = M_E_CPU0_SB_CA<3>
  224  VSS97  POWER  = GND
  225  CA5_B  IN  = M_E_CPU0_SB_CA<5>
  226  VSS98  POWER  = GND
  227  PAR_B  IN  = M_E_CPU0_SB_PAR
  228  VSS99  POWER  = GND
  229  CS1_B_N  IN  = M_E_CPU0_SB_CS_N<1>
  230  VSS100  POWER  = GND
  231  RFU5  TRI  = TP_CHE_CPU0_DIMM1_FRU_5
  232  RFU6  TRI  = TP_CHE_CPU0_DIMM1_FRU_6
  233  VSS101  POWER  = GND
  234  CB6_B  BI  = M_E_CPU0_SB_CB<6>
  235  VSS102  POWER  = GND
  236  CB7_B  BI  = M_E_CPU0_SB_CB<7>
  237  VSS103  POWER  = GND
  238  DQS4_B_C  BI  = M_E_CPU0_SB_DQS_DN<4>
  239  DQS4_B_T  BI  = M_E_CPU0_SB_DQS_DP<4>
  240  VSS104  POWER  = GND
  241  CB2_B  BI  = M_E_CPU0_SB_CB<2>
  242  VSS105  POWER  = GND
  243  CB3_B  BI  = M_E_CPU0_SB_CB<3>
  244  VSS106  POWER  = GND
  245  DQ2_B  BI  = M_E_CPU0_SB_DQ<2>
  246  VSS107  POWER  = GND
  247  DQ3_B  BI  = M_E_CPU0_SB_DQ<3>
  248  VSS108  POWER  = GND
  249  \dqs5_b_c||tdqs5_b_c\  BI  = M_E_CPU0_SB_DQS_DN<5>
  250  \dqs5_b_t||tdqs5_b_t\  BI  = M_E_CPU0_SB_DQS_DP<5>
  251  VSS109  POWER  = GND
  252  DQ6_B  BI  = M_E_CPU0_SB_DQ<6>
  253  VSS110  POWER  = GND
  254  DQ7_B  BI  = M_E_CPU0_SB_DQ<7>
  255  VSS111  POWER  = GND
  256  DQ10_B  BI  = M_E_CPU0_SB_DQ<10>
  257  VSS112  POWER  = GND
  258  DQ11_B  BI  = M_E_CPU0_SB_DQ<11>
  259  VSS113  POWER  = GND
  260  \dqs6_b_c||tdqs6_b_c\  BI  = M_E_CPU0_SB_DQS_DN<6>
  261  \dqs6_b_t||tdqs6_b_t\  BI  = M_E_CPU0_SB_DQS_DP<6>
  262  VSS114  POWER  = GND
  263  DQ14_B  BI  = M_E_CPU0_SB_DQ<14>
  264  VSS115  POWER  = GND
  265  DQ15_B  BI  = M_E_CPU0_SB_DQ<15>
  266  VSS116  POWER  = GND
  267  DQ18_B  BI  = M_E_CPU0_SB_DQ<18>
  268  VSS117  POWER  = GND
  269  DQ19_B  BI  = M_E_CPU0_SB_DQ<19>
  270  VSS118  POWER  = GND
  271  \dqs7_b_c||tdqs7_b_c\  BI  = M_E_CPU0_SB_DQS_DN<7>
  272  \dqs7_b_t||tdqs7_b_t\  BI  = M_E_CPU0_SB_DQS_DP<7>
  273  VSS119  POWER  = GND
  274  DQ22_B  BI  = M_E_CPU0_SB_DQ<22>
  275  VSS120  POWER  = GND
  276  DQ23_B  BI  = M_E_CPU0_SB_DQ<23>
  277  VSS121  POWER  = GND
  278  DQ26_B  BI  = M_E_CPU0_SB_DQ<26>
  279  VSS122  POWER  = GND
  280  DQ27_B  BI  = M_E_CPU0_SB_DQ<27>
  281  VSS123  POWER  = GND
  282  \dqs8_b_c||tdqs8_b_c\  BI  = M_E_CPU0_SB_DQS_DN<8>
  283  \dqs8_b_t||tdqs8_b_t\  BI  = M_E_CPU0_SB_DQS_DP<8>
  284  VSS124  POWER  = GND
  285  DQ30_B  BI  = M_E_CPU0_SB_DQ<30>
  286  VSS125  POWER  = GND
  287  DQ31_B  BI  = M_E_CPU0_SB_DQ<31>
  288  VSS126  POWER  = GND
  G1  G1  POWER  = GND
  G2  G2  POWER  = GND
  G3  G3  POWER  = GND
